# BASEBOARD_FAB2 (Tioga Pass) — schematic netlist excerpt (pin names and nets, part order shuffled) for the footprints in the layout excerpt that follows; sources: Cadence DE-HDL packaged netlist, KiCad conversion of Wiwynn_Tioga_Pass_MB.brd

C5D60  CAP_A  22.0UF 4V 20% X6S  pkg 0603V  page 217 : A = PVDDQ_ABC ; B = GND
C2G12  CAP_A  47UF 4V 20% X5R  pkg 0603V  page 225 : A = PVDDQ_GHJ ; B = GND
R4A9  RES  0.0 5% CHIP  pkg 0402  page 156 : A = SMB_LAN_STBY_LVC3_SCL ; B = SMB_PIROM_CPU0_SCL

(kicad_pcb
	(version 20260206)
	(generator "pcbnew")
	(generator_version "10.0")
	(general
		(thickness 1.6)
		(legacy_teardrops no)
	)
	(paper "A4")
	(title_block
		(title "Wiwynn_Tioga_Pass_MB.brd")
		(comment 1 "Tioga Pass / footprints 123-125 of 4770")
	)
	(layers
		(0 "F.Cu" signal "TOP")
		(4 "In1.Cu" signal "L2GND")
		(6 "In2.Cu" signal "L3")
		(8 "In3.Cu" signal "L4GND")
		(10 "In4.Cu" signal "L5")
		(12 "In5.Cu" signal "L6GND")
		(14 "In6.Cu" signal "L7VCC")
		(16 "In7.Cu" signal "L8VCC")
		(18 "In8.Cu" signal "L9GND")
		(20 "In9.Cu" signal "L10")
		(22 "In10.Cu" signal "L11GND")
		(24 "In11.Cu" signal "L12")
		(26 "In12.Cu" signal "L13GND")
		(2 "B.Cu" signal "BOTTOM")
		(9 "F.Adhes" user "F.Adhesive")
		(11 "B.Adhes" user "B.Adhesive")
		(13 "F.Paste" user "Package Geometry/Pastemask Top")
		(15 "B.Paste" user "Package Geometry/Pastemask Bottom")
		(5 "F.SilkS" user "Ref Des/Silkscreen Top")
		(7 "B.SilkS" user "Ref Des/Silkscreen Bottom")
		(1 "F.Mask" user "Board Geometry/Soldermask Top")
		(3 "B.Mask" user "Board Geometry/Soldermask Bottom")
		(17 "Dwgs.User" user "User.Drawings")
		(19 "Cmts.User" user "User.Comments")
		(21 "Eco1.User" user "User.Eco1")
		(23 "Eco2.User" user "User.Eco2")
		(25 "Edge.Cuts" user "Board Geometry/Outline")
		(27 "Margin" user)
		(31 "F.CrtYd" user "Package Geometry/Place Bound Top")
		(29 "B.CrtYd" user "Package Geometry/Place Bound Bottom")
		(35 "F.Fab" user "Ref Des/Assembly Top")
		(33 "B.Fab" user "Ref Des/Assembly Bottom")
	)
	(footprint ""
		(layer "F.Cu")
		(at 88.392 -3.3528 90)
		(property "Reference" "C2G12"
			(at 1.848866 0.752348 90)
			(unlocked yes)
			(layer "F.SilkS")
			(effects
				(font
					(size 1.27 0.9652)
					(thickness 0.1524)
				)
			)
		)
		(property "Value" ""
			(at 0 0 90)
			(layer "F.Fab")
			(effects
				(font
					(size 1.27 1.27)
				)
			)
		)
		(duplicate_pad_numbers_are_jumpers no)
		(fp_rect
			(start -0.500126 1.598422)
			(end 0.500126 -0.201422)
			(stroke
				(width 0)
				(type default)
			)
			(fill no)
			(layer "F.CrtYd")
		)
		(fp_line
			(start 0.500126 -0.201422)
			(end 0.500126 1.598422)
			(stroke
				(width 0.1)
				(type default)
			)
			(layer "F.Fab")
		)
		(fp_line
			(start -0.500126 -0.201422)
			(end 0.500126 -0.201422)
			(stroke
				(width 0.1)
				(type default)
			)
			(layer "F.Fab")
		)
		(fp_line
			(start 0.500126 1.598422)
			(end -0.500126 1.598422)
			(stroke
				(width 0.1)
				(type default)
			)
			(layer "F.Fab")
		)
		(fp_line
			(start -0.500126 1.598422)
			(end -0.500126 -0.201422)
			(stroke
				(width 0.1)
				(type default)
			)
			(layer "F.Fab")
		)
		(pad "1" smd rect
			(at 0 0)
			(size 0.889 0.9906)
			(layers "F.Cu" "F.Mask" "F.Paste")
			(net "PVDDQ_GHJ")
		)
		(pad "2" smd rect
			(at 0 1.397)
			(size 0.889 0.9906)
			(layers "F.Cu" "F.Mask" "F.Paste")
			(net "GND")
		)
		(zone
			(layer "F.Cu")
			(hatch none 0.5)
			(connect_pads
				(clearance 0)
			)
			(min_thickness 0.25)
			(keepout
				(tracks allowed)
				(vias not_allowed)
				(pads allowed)
				(copperpour not_allowed)
				(footprints allowed)
			)
			(placement
				(enabled no)
				(sheetname "")
			)
			(fill
				(thermal_gap 0.5)
				(thermal_bridge_width 0.5)
				(island_removal_mode 0)
			)
			(polygon
				(pts
					(xy 89.3445 -2.8575) (xy 89.3445 -3.8481) (xy 88.8365 -3.8481) (xy 88.8365 -2.8575)
				)
			)
		)
		(zone
			(layer "F.Cu")
			(hatch none 0.5)
			(connect_pads
				(clearance 0)
			)
			(min_thickness 0.25)
			(keepout
				(tracks not_allowed)
				(vias allowed)
				(pads allowed)
				(copperpour not_allowed)
				(footprints allowed)
			)
			(placement
				(enabled no)
				(sheetname "")
			)
			(fill
				(thermal_gap 0.5)
				(thermal_bridge_width 0.5)
				(island_removal_mode 0)
			)
			(polygon
				(pts
					(xy 89.3445 -2.8575) (xy 89.3445 -3.8481) (xy 88.8365 -3.8481) (xy 88.8365 -2.8575)
				)
			)
		)
	)
	(footprint ""
		(layer "F.Cu")
		(at 178.98237 -144.159224 90)
		(property "Reference" "R4A9"
			(at 0 0 90)
			(layer "F.SilkS")
			(hide yes)
			(effects
				(font
					(size 1.27 1.27)
				)
			)
		)
		(property "Value" ""
			(at 0 0 90)
			(layer "F.Fab")
			(effects
				(font
					(size 1.27 1.27)
				)
			)
		)
		(duplicate_pad_numbers_are_jumpers no)
		(fp_poly
			(pts
				(xy -0.2794 -0.1016) (xy 0.2794 -0.1016) (xy 0.2794 0.9906) (xy -0.2794 0.9906)
			)
			(stroke
				(width 0)
				(type default)
			)
			(fill no)
			(layer "F.CrtYd")
		)
		(fp_line
			(start 0.2794 -0.1016)
			(end -0.2794 -0.1016)
			(stroke
				(width 0.1)
				(type default)
			)
			(layer "F.Fab")
		)
		(fp_line
			(start -0.2794 -0.1016)
			(end -0.2794 0.9906)
			(stroke
				(width 0.1)
				(type default)
			)
			(layer "F.Fab")
		)
		(fp_line
			(start 0.2794 0.9906)
			(end 0.2794 -0.1016)
			(stroke
				(width 0.1)
				(type default)
			)
			(layer "F.Fab")
		)
		(fp_line
			(start -0.2794 0.9906)
			(end 0.2794 0.9906)
			(stroke
				(width 0.1)
				(type default)
			)
			(layer "F.Fab")
		)
		(pad "1" smd rect
			(at 0 0 90)
			(size 0.508 0.508)
			(layers "F.Cu" "F.Mask" "F.Paste")
			(net "SMB_LAN_STBY_LVC3_SCL")
		)
		(pad "2" smd rect
			(at 0 0.889 90)
			(size 0.508 0.508)
			(layers "F.Cu" "F.Mask" "F.Paste")
			(net "SMB_PIROM_CPU0_SCL")
		)
		(zone
			(layer "F.Cu")
			(hatch none 0.5)
			(connect_pads
				(clearance 0)
			)
			(min_thickness 0.25)
			(keepout
				(tracks allowed)
				(vias not_allowed)
				(pads allowed)
				(copperpour not_allowed)
				(footprints allowed)
			)
			(placement
				(enabled no)
				(sheetname "")
			)
			(fill
				(thermal_gap 0.5)
				(thermal_bridge_width 0.5)
				(island_removal_mode 0)
			)
			(polygon
				(pts
					(xy 179.23637 -143.905224) (xy 179.23637 -144.413224) (xy 179.61737 -144.413224) (xy 179.61737 -143.905224)
				)
			)
		)
		(zone
			(layer "F.Cu")
			(hatch none 0.5)
			(connect_pads
				(clearance 0)
			)
			(min_thickness 0.25)
			(keepout
				(tracks not_allowed)
				(vias allowed)
				(pads allowed)
				(copperpour not_allowed)
				(footprints allowed)
			)
			(placement
				(enabled no)
				(sheetname "")
			)
			(fill
				(thermal_gap 0.5)
				(thermal_bridge_width 0.5)
				(island_removal_mode 0)
			)
			(polygon
				(pts
					(xy 179.61737 -143.905224) (xy 179.61737 -144.413224) (xy 179.23637 -144.413224) (xy 179.23637 -143.905224)
				)
			)
		)
	)
	(footprint ""
		(layer "F.Cu")
		(at 270.890238 -68.365116 180)
		(property "Reference" "C5D60"
			(at 0 0 180)
			(layer "F.SilkS")
			(hide yes)
			(effects
				(font
					(size 1.27 1.27)
				)
			)
		)
		(property "Value" ""
			(at 0 0 180)
			(layer "F.Fab")
			(effects
				(font
					(size 1.27 1.27)
				)
			)
		)
		(duplicate_pad_numbers_are_jumpers no)
		(fp_poly
			(pts
				(xy -0.4953 -0.2032) (xy 0.4953 -0.2032) (xy 0.4953 1.6002) (xy -0.4953 1.6002)
			)
			(stroke
				(width 0)
				(type default)
			)
			(fill no)
			(layer "F.CrtYd")
		)
		(fp_line
			(start 0.4953 1.6002)
			(end -0.4953 1.6002)
			(stroke
				(width 0.1)
				(type default)
			)
			(layer "F.Fab")
		)
		(fp_line
			(start 0.4953 -0.2032)
			(end 0.4953 1.6002)
			(stroke
				(width 0.1)
				(type default)
			)
			(layer "F.Fab")
		)
		(fp_line
			(start -0.4953 1.6002)
			(end -0.4953 -0.2032)
			(stroke
				(width 0.1)
				(type default)
			)
			(layer "F.Fab")
		)
		(fp_line
			(start -0.4953 -0.2032)
			(end 0.4953 -0.2032)
			(stroke
				(width 0.1)
				(type default)
			)
			(layer "F.Fab")
		)
		(pad "1" smd rect
			(at 0 0 180)
			(size 0.762 0.889)
			(layers "F.Cu" "F.Mask" "F.Paste")
			(net "PVDDQ_ABC")
		)
		(pad "2" smd rect
			(at 0 1.397 180)
			(size 0.762 0.889)
			(layers "F.Cu" "F.Mask" "F.Paste")
			(net "GND")
		)
		(zone
			(layer "F.Cu")
			(hatch none 0.5)
			(connect_pads
				(clearance 0)
			)
			(min_thickness 0.25)
			(keepout
				(tracks not_allowed)
				(vias allowed)
				(pads allowed)
				(copperpour not_allowed)
				(footprints allowed)
			)
			(placement
				(enabled no)
				(sheetname "")
			)
			(fill
				(thermal_gap 0.5)
				(thermal_bridge_width 0.5)
				(island_removal_mode 0)
			)
			(polygon
				(pts
					(xy 271.271238 -68.809616) (xy 270.509238 -68.809616) (xy 270.509238 -69.317616) (xy 271.271238 -69.317616)
				)
			)
		)
	)
)
